# S9S_MB_2U (Grand Teton) — schematic netlist excerpt (pin names and nets, part order shuffled) for the footprints in the layout excerpt that follows; sources: Cadence DE-HDL packaged netlist, KiCad conversion of 03242023_DA0F0TMBIJ0_F0T_Motherboard_J_brd_V01_OCP.brd

R2370  Q_RES  0 5% CHIP  pkg 0402LF  page 266 : A = SVID_ALERT0_CPU0_R_N ; B = SVID_ALERT_PVCCIN_CPU0_R
C2380  Q_CAP  100NF 50V 10% EMPTY  pkg C0402  page 307 : A = UV_P2V5_COMP ; B = GND

(kicad_pcb
	(version 20260206)
	(generator "pcbnew")
	(generator_version "10.0")
	(general
		(thickness 1.6)
		(legacy_teardrops no)
	)
	(paper "A4")
	(title_block
		(title "03242023_DA0F0TMBIJ0_F0T_Motherboard_J_brd_V01_OCP.brd")
		(comment 1 "Grand Teton / footprints 3852-3853 of 6105")
	)
	(layers
		(0 "F.Cu" signal "TOP")
		(4 "In1.Cu" signal "GND")
		(6 "In2.Cu" signal "IN1")
		(8 "In3.Cu" signal "GND1")
		(10 "In4.Cu" signal "IN2")
		(12 "In5.Cu" signal "GND2")
		(14 "In6.Cu" signal "IN3")
		(16 "In7.Cu" signal "GND3")
		(18 "In8.Cu" signal "VCC")
		(20 "In9.Cu" signal "VCC1")
		(22 "In10.Cu" signal "GND4")
		(24 "In11.Cu" signal "IN4")
		(26 "In12.Cu" signal "GND5")
		(28 "In13.Cu" signal "IN5")
		(30 "In14.Cu" signal "GND6")
		(32 "In15.Cu" signal "IN6")
		(34 "In16.Cu" signal "GND7")
		(2 "B.Cu" signal "BOTTOM")
		(9 "F.Adhes" user "F.Adhesive")
		(11 "B.Adhes" user "B.Adhesive")
		(13 "F.Paste" user "Package Geometry/Pastemask Top")
		(15 "B.Paste" user "Package Geometry/Pastemask Bottom")
		(5 "F.SilkS" user "Ref Des/Silkscreen Top")
		(7 "B.SilkS" user "Ref Des/Silkscreen Bottom")
		(1 "F.Mask" user "Board Geometry/Soldermask Top")
		(3 "B.Mask" user "Board Geometry/Soldermask Bottom")
		(17 "Dwgs.User" user "User.Drawings")
		(19 "Cmts.User" user "User.Comments")
		(21 "Eco1.User" user "User.Eco1")
		(23 "Eco2.User" user "User.Eco2")
		(25 "Edge.Cuts" user "Board Geometry/Outline")
		(27 "Margin" user)
		(31 "F.CrtYd" user "Package Geometry/Place Bound Top")
		(29 "B.CrtYd" user "Package Geometry/Place Bound Bottom")
		(35 "F.Fab" user "Ref Des/Assembly Top")
		(33 "B.Fab" user "Ref Des/Assembly Bottom")
	)
	(footprint ""
		(layer "F.Cu")
		(at 208.1022 -114.0968 180)
		(property "Reference" "C2380"
			(at 0 0 180)
			(layer "F.SilkS")
			(hide yes)
			(effects
				(font
					(size 1.27 1.27)
				)
			)
		)
		(property "Value" ""
			(at 0 0 180)
			(layer "F.Fab")
			(effects
				(font
					(size 1.27 1.27)
				)
			)
		)
		(duplicate_pad_numbers_are_jumpers no)
		(fp_line
			(start 0.7874 0.4064)
			(end -0.7874 0.4064)
			(stroke
				(width 0.1524)
				(type default)
			)
			(layer "F.SilkS")
		)
		(fp_line
			(start 0.7874 -0.4064)
			(end 0.7874 0.4064)
			(stroke
				(width 0.1524)
				(type default)
			)
			(layer "F.SilkS")
		)
		(fp_line
			(start -0.7874 0.4064)
			(end -0.7874 -0.4064)
			(stroke
				(width 0.1524)
				(type default)
			)
			(layer "F.SilkS")
		)
		(fp_line
			(start -0.7874 -0.4064)
			(end 0.7874 -0.4064)
			(stroke
				(width 0.1524)
				(type default)
			)
			(layer "F.SilkS")
		)
		(fp_line
			(start 0.67945 0.3048)
			(end 0.120396 0.3048)
			(stroke
				(width 0.1)
				(type default)
			)
			(layer "F.Fab")
		)
		(fp_line
			(start 0.67945 -0.3048)
			(end 0.67945 0.3048)
			(stroke
				(width 0.1)
				(type default)
			)
			(layer "F.Fab")
		)
		(fp_line
			(start 0.12065 -0.2794)
			(end 0.12065 -0.3048)
			(stroke
				(width 0.1)
				(type default)
			)
			(layer "F.Fab")
		)
		(fp_line
			(start 0.12065 -0.3048)
			(end 0.67945 -0.3048)
			(stroke
				(width 0.1)
				(type default)
			)
			(layer "F.Fab")
		)
		(fp_line
			(start 0.120396 0.3048)
			(end 0.120396 0.2794)
			(stroke
				(width 0.1)
				(type default)
			)
			(layer "F.Fab")
		)
		(fp_line
			(start 0.120396 0.2794)
			(end -0.12065 0.2794)
			(stroke
				(width 0.1)
				(type default)
			)
			(layer "F.Fab")
		)
		(fp_line
			(start -0.12065 0.3048)
			(end -0.67945 0.3048)
			(stroke
				(width 0.1)
				(type default)
			)
			(layer "F.Fab")
		)
		(fp_line
			(start -0.12065 0.2794)
			(end -0.12065 0.3048)
			(stroke
				(width 0.1)
				(type default)
			)
			(layer "F.Fab")
		)
		(fp_line
			(start -0.12065 -0.2794)
			(end 0.12065 -0.2794)
			(stroke
				(width 0.1)
				(type default)
			)
			(layer "F.Fab")
		)
		(fp_line
			(start -0.12065 -0.305054)
			(end -0.12065 -0.2794)
			(stroke
				(width 0.1)
				(type default)
			)
			(layer "F.Fab")
		)
		(fp_line
			(start -0.67945 0.3048)
			(end -0.67945 -0.305054)
			(stroke
				(width 0.1)
				(type default)
			)
			(layer "F.Fab")
		)
		(fp_line
			(start -0.67945 -0.305054)
			(end -0.12065 -0.305054)
			(stroke
				(width 0.1)
				(type default)
			)
			(layer "F.Fab")
		)
		(pad "1" smd circle
			(at -0.40005 0 180)
			(size 0 0)
			(layers "F.Cu" "F.Mask" "F.Paste")
			(net "UV_P2V5_COMP")
		)
		(pad "2" smd circle
			(at 0.40005 0 180)
			(size 0 0)
			(layers "F.Cu" "F.Mask" "F.Paste")
			(net "GND")
		)
	)
	(footprint ""
		(layer "F.Cu")
		(at 350.78543 -355.773736)
		(property "Reference" "R2370"
			(at 0 0 0)
			(layer "F.SilkS")
			(hide yes)
			(effects
				(font
					(size 1.27 1.27)
				)
			)
		)
		(property "Value" ""
			(at 0 0 0)
			(layer "F.Fab")
			(effects
				(font
					(size 1.27 1.27)
				)
			)
		)
		(duplicate_pad_numbers_are_jumpers no)
		(fp_line
			(start -0.7874 -0.4064)
			(end 0.7874 -0.4064)
			(stroke
				(width 0.1524)
				(type default)
			)
			(layer "F.SilkS")
		)
		(fp_line
			(start -0.7874 0.4064)
			(end -0.7874 -0.4064)
			(stroke
				(width 0.1524)
				(type default)
			)
			(layer "F.SilkS")
		)
		(fp_line
			(start 0.7874 -0.4064)
			(end 0.7874 0.4064)
			(stroke
				(width 0.1524)
				(type default)
			)
			(layer "F.SilkS")
		)
		(fp_line
			(start 0.7874 0.4064)
			(end -0.7874 0.4064)
			(stroke
				(width 0.1524)
				(type default)
			)
			(layer "F.SilkS")
		)
		(fp_line
			(start -0.67945 -0.305054)
			(end -0.12065 -0.305054)
			(stroke
				(width 0.1)
				(type default)
			)
			(layer "F.Fab")
		)
		(fp_line
			(start -0.67945 0.3048)
			(end -0.67945 -0.305054)
			(stroke
				(width 0.1)
				(type default)
			)
			(layer "F.Fab")
		)
		(fp_line
			(start -0.12065 -0.305054)
			(end -0.12065 -0.2794)
			(stroke
				(width 0.1)
				(type default)
			)
			(layer "F.Fab")
		)
		(fp_line
			(start -0.12065 -0.2794)
			(end 0.12065 -0.2794)
			(stroke
				(width 0.1)
				(type default)
			)
			(layer "F.Fab")
		)
		(fp_line
			(start -0.12065 0.2794)
			(end -0.12065 0.3048)
			(stroke
				(width 0.1)
				(type default)
			)
			(layer "F.Fab")
		)
		(fp_line
			(start -0.12065 0.3048)
			(end -0.67945 0.3048)
			(stroke
				(width 0.1)
				(type default)
			)
			(layer "F.Fab")
		)
		(fp_line
			(start 0.120396 0.2794)
			(end -0.12065 0.2794)
			(stroke
				(width 0.1)
				(type default)
			)
			(layer "F.Fab")
		)
		(fp_line
			(start 0.120396 0.3048)
			(end 0.120396 0.2794)
			(stroke
				(width 0.1)
				(type default)
			)
			(layer "F.Fab")
		)
		(fp_line
			(start 0.12065 -0.3048)
			(end 0.67945 -0.3048)
			(stroke
				(width 0.1)
				(type default)
			)
			(layer "F.Fab")
		)
		(fp_line
			(start 0.12065 -0.2794)
			(end 0.12065 -0.3048)
			(stroke
				(width 0.1)
				(type default)
			)
			(layer "F.Fab")
		)
		(fp_line
			(start 0.67945 -0.3048)
			(end 0.67945 0.3048)
			(stroke
				(width 0.1)
				(type default)
			)
			(layer "F.Fab")
		)
		(fp_line
			(start 0.67945 0.3048)
			(end 0.120396 0.3048)
			(stroke
				(width 0.1)
				(type default)
			)
			(layer "F.Fab")
		)
		(pad "1" smd circle
			(at -0.40005 0)
			(size 0 0)
			(layers "F.Cu" "F.Mask" "F.Paste")
			(net "SVID_ALERT0_CPU0_R_N")
		)
		(pad "2" smd circle
			(at 0.40005 0)
			(size 0 0)
			(layers "F.Cu" "F.Mask" "F.Paste")
			(net "SVID_ALERT_PVCCIN_CPU0_R")
		)
	)
)
